(kicad_pcb
	(version 20260206)
	(generator "pcbnew")
	(generator_version "10.0")
	(general
		(thickness 1.6)
		(legacy_teardrops no)
	)
	(paper "A4")
	(title_block
		(title "baseboard — 13948-1b.1110WZS1818.brd")
		(comment 1 "Honey Badger (Wiwynn) / footprints 2114-2123 of 2523")
	)
	(layers
		(0 "F.Cu" signal "TOP")
		(4 "In1.Cu" signal "L2GND")
		(6 "In2.Cu" signal "L3")
		(8 "In3.Cu" signal "L4VCC")
		(10 "In4.Cu" signal "L5VCC")
		(12 "In5.Cu" signal "L6")
		(14 "In6.Cu" signal "L7GND")
		(2 "B.Cu" signal "BOTTOM")
		(9 "F.Adhes" user "F.Adhesive")
		(11 "B.Adhes" user "B.Adhesive")
		(13 "F.Paste" user "Package Geometry/Pastemask Top")
		(15 "B.Paste" user "Package Geometry/Pastemask Bottom")
		(5 "F.SilkS" user "Ref Des/Silkscreen Top")
		(7 "B.SilkS" user "Ref Des/Silkscreen Bottom")
		(1 "F.Mask" user "Board Geometry/Soldermask Top")
		(3 "B.Mask" user "Board Geometry/Soldermask Bottom")
		(17 "Dwgs.User" user "User.Drawings")
		(19 "Cmts.User" user "User.Comments")
		(21 "Eco1.User" user "User.Eco1")
		(23 "Eco2.User" user "User.Eco2")
		(25 "Edge.Cuts" user "Board Geometry/Outline")
		(27 "Margin" user)
		(31 "F.CrtYd" user "Package Geometry/Place Bound Top")
		(29 "B.CrtYd" user "Package Geometry/Place Bound Bottom")
		(35 "F.Fab" user "Ref Des/Assembly Top")
		(33 "B.Fab" user "Ref Des/Assembly Bottom")
	)
	(footprint ""
		(layer "B.Cu")
		(at 318.008 -165.354 -90)
		(property "Reference" "R243"
			(at 0 0 90)
			(layer "B.SilkS")
			(hide yes)
			(effects
				(font
					(size 1.27 1.27)
				)
				(justify mirror)
			)
		)
		(property "Value" "0R2J-2-GP"
			(at -0.064008 -3.993896 270)
			(unlocked yes)
			(layer "B.Fab")
			(hide yes)
			(effects
				(font
					(size 1.016 1.016)
					(thickness 0.1524)
				)
				(justify mirror)
			)
		)
		(property "Device Type" "R402H16"
			(at -0.064008 -5.517896 270)
			(unlocked yes)
			(layer "B.Fab")
			(hide yes)
			(effects
				(font
					(size 1.016 1.016)
					(thickness 0.1524)
				)
				(justify mirror)
			)
		)
		(duplicate_pad_numbers_are_jumpers no)
		(fp_line
			(start -0.508 -0.9398)
			(end 0.508 -0.9398)
			(stroke
				(width 0.1524)
				(type default)
			)
			(layer "B.SilkS")
		)
		(fp_line
			(start 0.508 -0.9398)
			(end 0.508 0.9398)
			(stroke
				(width 0.1524)
				(type default)
			)
			(layer "B.SilkS")
		)
		(fp_rect
			(start 0.508 0.9398)
			(end -0.508 -0.9398)
			(stroke
				(width 0)
				(type default)
			)
			(fill no)
			(layer "B.CrtYd")
		)
		(fp_rect
			(start 0.508 0.9398)
			(end -0.508 -0.9398)
			(stroke
				(width 0)
				(type default)
			)
			(fill no)
			(layer "B.Fab")
		)
		(pad "1" smd custom
			(at 0 -0.4445 90)
			(size 0.1397 0.1397)
			(layers "B.Cu" "B.Mask" "B.Paste")
			(net "BMC_I2C_D_SDA")
			(options
				(clearance outline)
				(anchor circle)
			)
			(primitives
				(gr_poly
					(pts
						(arc
							(start -0.1778 0.2794)
							(mid -0.249642 0.249642)
							(end -0.2794 0.1778)
						)
						(arc
							(start -0.2794 -0.1778)
							(mid -0.249642 -0.249642)
							(end -0.1778 -0.2794)
						)
						(arc
							(start 0.1778 -0.2794)
							(mid 0.249642 -0.249642)
							(end 0.2794 -0.1778)
						)
						(arc
							(start 0.2794 0.1778)
							(mid 0.249642 0.249642)
							(end 0.1778 0.2794)
						)
					)
					(width 0)
					(fill yes)
				)
			)
		)
		(pad "2" smd custom
			(at 0 0.4445 90)
			(size 0.1397 0.1397)
			(layers "B.Cu" "B.Mask" "B.Paste")
			(net "BMC0_SMB3_DAT")
			(options
				(clearance outline)
				(anchor circle)
			)
			(primitives
				(gr_poly
					(pts
						(arc
							(start -0.1778 0.2794)
							(mid -0.249642 0.249642)
							(end -0.2794 0.1778)
						)
						(arc
							(start -0.2794 -0.1778)
							(mid -0.249642 -0.249642)
							(end -0.1778 -0.2794)
						)
						(arc
							(start 0.1778 -0.2794)
							(mid 0.249642 -0.249642)
							(end 0.2794 -0.1778)
						)
						(arc
							(start 0.2794 0.1778)
							(mid 0.249642 0.249642)
							(end 0.1778 0.2794)
						)
					)
					(width 0)
					(fill yes)
				)
			)
		)
	)
	(footprint ""
		(layer "B.Cu")
		(at 110.50016 -32.512)
		(property "Reference" "STP92"
			(at 0 0 0)
			(layer "B.SilkS")
			(hide yes)
			(effects
				(font
					(size 1.27 1.27)
				)
				(justify mirror)
			)
		)
		(property "Value" "TPAD28"
			(at -0.0127 -1.8034 0)
			(unlocked yes)
			(layer "B.Fab")
			(hide yes)
			(effects
				(font
					(size 1.016 1.016)
					(thickness 0.1524)
				)
				(justify mirror)
			)
		)
		(property "Device Type" "TPAD28"
			(at -0.0127 -3.3274 0)
			(unlocked yes)
			(layer "B.Fab")
			(hide yes)
			(effects
				(font
					(size 1.016 1.016)
					(thickness 0.1524)
				)
				(justify mirror)
			)
		)
		(duplicate_pad_numbers_are_jumpers no)
		(fp_poly
			(pts
				(arc
					(start 0.3556 0)
					(mid -0.3556 0)
					(end 0.3556 0)
				)
			)
			(stroke
				(width 0)
				(type default)
			)
			(fill no)
			(layer "B.CrtYd")
		)
		(fp_poly
			(pts
				(arc
					(start 0.6096 0)
					(mid -0.6096 0)
					(end 0.6096 0)
				)
			)
			(stroke
				(width 0)
				(type default)
			)
			(fill no)
			(layer "B.Fab")
		)
		(pad "1" smd circle
			(at 0 0 180)
			(size 0.7112 0.7112)
			(layers "B.Cu" "B.Mask" "B.Paste")
			(net "IOC_GPIO_14")
		)
	)
	(footprint ""
		(layer "B.Cu")
		(at 318.008 -172.593 -90)
		(property "Reference" "R467"
			(at 0 0 90)
			(layer "B.SilkS")
			(hide yes)
			(effects
				(font
					(size 1.27 1.27)
				)
				(justify mirror)
			)
		)
		(property "Value" "0R2J-2-GP"
			(at -0.064008 -3.993896 270)
			(unlocked yes)
			(layer "B.Fab")
			(hide yes)
			(effects
				(font
					(size 1.016 1.016)
					(thickness 0.1524)
				)
				(justify mirror)
			)
		)
		(property "Device Type" "R402H16"
			(at -0.064008 -5.517896 270)
			(unlocked yes)
			(layer "B.Fab")
			(hide yes)
			(effects
				(font
					(size 1.016 1.016)
					(thickness 0.1524)
				)
				(justify mirror)
			)
		)
		(duplicate_pad_numbers_are_jumpers no)
		(fp_line
			(start -0.508 -0.9398)
			(end 0.508 -0.9398)
			(stroke
				(width 0.1524)
				(type default)
			)
			(layer "B.SilkS")
		)
		(fp_line
			(start 0.508 -0.9398)
			(end 0.508 0.9398)
			(stroke
				(width 0.1524)
				(type default)
			)
			(layer "B.SilkS")
		)
		(fp_rect
			(start 0.508 0.9398)
			(end -0.508 -0.9398)
			(stroke
				(width 0)
				(type default)
			)
			(fill no)
			(layer "B.CrtYd")
		)
		(fp_rect
			(start 0.508 0.9398)
			(end -0.508 -0.9398)
			(stroke
				(width 0)
				(type default)
			)
			(fill no)
			(layer "B.Fab")
		)
		(pad "1" smd custom
			(at 0 -0.4445 90)
			(size 0.1397 0.1397)
			(layers "B.Cu" "B.Mask" "B.Paste")
			(net "BMC_I2C_F_SDA")
			(options
				(clearance outline)
				(anchor circle)
			)
			(primitives
				(gr_poly
					(pts
						(arc
							(start -0.1778 0.2794)
							(mid -0.249642 0.249642)
							(end -0.2794 0.1778)
						)
						(arc
							(start -0.2794 -0.1778)
							(mid -0.249642 -0.249642)
							(end -0.1778 -0.2794)
						)
						(arc
							(start 0.1778 -0.2794)
							(mid 0.249642 -0.249642)
							(end 0.2794 -0.1778)
						)
						(arc
							(start 0.2794 0.1778)
							(mid 0.249642 0.249642)
							(end 0.1778 0.2794)
						)
					)
					(width 0)
					(fill yes)
				)
			)
		)
		(pad "2" smd custom
			(at 0 0.4445 90)
			(size 0.1397 0.1397)
			(layers "B.Cu" "B.Mask" "B.Paste")
			(net "BMC0_SMB8_DAT")
			(options
				(clearance outline)
				(anchor circle)
			)
			(primitives
				(gr_poly
					(pts
						(arc
							(start -0.1778 0.2794)
							(mid -0.249642 0.249642)
							(end -0.2794 0.1778)
						)
						(arc
							(start -0.2794 -0.1778)
							(mid -0.249642 -0.249642)
							(end -0.1778 -0.2794)
						)
						(arc
							(start 0.1778 -0.2794)
							(mid 0.249642 -0.249642)
							(end 0.2794 -0.1778)
						)
						(arc
							(start 0.2794 0.1778)
							(mid 0.249642 0.249642)
							(end 0.1778 0.2794)
						)
					)
					(width 0)
					(fill yes)
				)
			)
		)
	)
	(footprint ""
		(layer "B.Cu")
		(at 116.420646 -34.991548)
		(property "Reference" "STP136"
			(at 0 0 0)
			(layer "B.SilkS")
			(hide yes)
			(effects
				(font
					(size 1.27 1.27)
				)
				(justify mirror)
			)
		)
		(property "Value" "TPAD28"
			(at -0.0127 -1.8034 0)
			(unlocked yes)
			(layer "B.Fab")
			(hide yes)
			(effects
				(font
					(size 1.016 1.016)
					(thickness 0.1524)
				)
				(justify mirror)
			)
		)
		(property "Device Type" "TPAD28"
			(at -0.0127 -3.3274 0)
			(unlocked yes)
			(layer "B.Fab")
			(hide yes)
			(effects
				(font
					(size 1.016 1.016)
					(thickness 0.1524)
				)
				(justify mirror)
			)
		)
		(duplicate_pad_numbers_are_jumpers no)
		(fp_poly
			(pts
				(arc
					(start 0.3556 0)
					(mid -0.3556 0)
					(end 0.3556 0)
				)
			)
			(stroke
				(width 0)
				(type default)
			)
			(fill no)
			(layer "B.CrtYd")
		)
		(fp_poly
			(pts
				(arc
					(start 0.6096 0)
					(mid -0.6096 0)
					(end 0.6096 0)
				)
			)
			(stroke
				(width 0)
				(type default)
			)
			(fill no)
			(layer "B.Fab")
		)
		(pad "1" smd circle
			(at 0 0 180)
			(size 0.7112 0.7112)
			(layers "B.Cu" "B.Mask" "B.Paste")
			(net "IOC_GPIO_16")
		)
	)
	(footprint ""
		(layer "B.Cu")
		(at 301.58182 -181.79288)
		(property "Reference" "TP160"
			(at 0 0 0)
			(layer "B.SilkS")
			(hide yes)
			(effects
				(font
					(size 1.27 1.27)
				)
				(justify mirror)
			)
		)
		(property "Value" "TPAD28"
			(at -0.0127 -1.8034 0)
			(unlocked yes)
			(layer "B.Fab")
			(hide yes)
			(effects
				(font
					(size 1.016 1.016)
					(thickness 0.1524)
				)
				(justify mirror)
			)
		)
		(property "Device Type" "TPAD28"
			(at -0.0127 -3.3274 0)
			(unlocked yes)
			(layer "B.Fab")
			(hide yes)
			(effects
				(font
					(size 1.016 1.016)
					(thickness 0.1524)
				)
				(justify mirror)
			)
		)
		(duplicate_pad_numbers_are_jumpers no)
		(fp_poly
			(pts
				(arc
					(start 0.3556 0)
					(mid -0.3556 0)
					(end 0.3556 0)
				)
			)
			(stroke
				(width 0)
				(type default)
			)
			(fill no)
			(layer "B.CrtYd")
		)
		(fp_poly
			(pts
				(arc
					(start 0.6096 0)
					(mid -0.6096 0)
					(end 0.6096 0)
				)
			)
			(stroke
				(width 0)
				(type default)
			)
			(fill no)
			(layer "B.Fab")
		)
		(pad "1" smd circle
			(at 0 0 180)
			(size 0.7112 0.7112)
			(layers "B.Cu" "B.Mask" "B.Paste")
			(net "TP_BMC_GPIOJ5")
		)
	)
	(footprint ""
		(layer "B.Cu")
		(at 88.14816 -49.022)
		(property "Reference" "STP16"
			(at 0 0 0)
			(layer "B.SilkS")
			(hide yes)
			(effects
				(font
					(size 1.27 1.27)
				)
				(justify mirror)
			)
		)
		(property "Value" "TPAD28"
			(at -0.0127 -1.8034 0)
			(unlocked yes)
			(layer "B.Fab")
			(hide yes)
			(effects
				(font
					(size 1.016 1.016)
					(thickness 0.1524)
				)
				(justify mirror)
			)
		)
		(property "Device Type" "TPAD28"
			(at -0.0127 -3.3274 0)
			(unlocked yes)
			(layer "B.Fab")
			(hide yes)
			(effects
				(font
					(size 1.016 1.016)
					(thickness 0.1524)
				)
				(justify mirror)
			)
		)
		(duplicate_pad_numbers_are_jumpers no)
		(fp_poly
			(pts
				(arc
					(start 0.3556 0)
					(mid -0.3556 0)
					(end 0.3556 0)
				)
			)
			(stroke
				(width 0)
				(type default)
			)
			(fill no)
			(layer "B.CrtYd")
		)
		(fp_poly
			(pts
				(arc
					(start 0.6096 0)
					(mid -0.6096 0)
					(end 0.6096 0)
				)
			)
			(stroke
				(width 0)
				(type default)
			)
			(fill no)
			(layer "B.Fab")
		)
		(pad "1" smd circle
			(at 0 0 180)
			(size 0.7112 0.7112)
			(layers "B.Cu" "B.Mask" "B.Paste")
			(net "SIO_DOUT_1")
		)
	)
	(footprint ""
		(layer "B.Cu")
		(at 310.896 -186.817 90)
		(property "Reference" "R302"
			(at 0 0 90)
			(layer "B.SilkS")
			(hide yes)
			(effects
				(font
					(size 1.27 1.27)
				)
				(justify mirror)
			)
		)
		(property "Value" "0R2J-2-GP"
			(at -0.064008 -3.993896 90)
			(unlocked yes)
			(layer "B.Fab")
			(hide yes)
			(effects
				(font
					(size 1.016 1.016)
					(thickness 0.1524)
				)
				(justify mirror)
			)
		)
		(property "Device Type" "R402H16"
			(at -0.064008 -5.517896 90)
			(unlocked yes)
			(layer "B.Fab")
			(hide yes)
			(effects
				(font
					(size 1.016 1.016)
					(thickness 0.1524)
				)
				(justify mirror)
			)
		)
		(duplicate_pad_numbers_are_jumpers no)
		(fp_line
			(start 0.508 -0.9398)
			(end 0.508 0.9398)
			(stroke
				(width 0.1524)
				(type default)
			)
			(layer "B.SilkS")
		)
		(fp_line
			(start -0.508 -0.9398)
			(end 0.508 -0.9398)
			(stroke
				(width 0.1524)
				(type default)
			)
			(layer "B.SilkS")
		)
		(fp_rect
			(start 0.508 0.9398)
			(end -0.508 -0.9398)
			(stroke
				(width 0)
				(type default)
			)
			(fill no)
			(layer "B.CrtYd")
		)
		(fp_rect
			(start 0.508 0.9398)
			(end -0.508 -0.9398)
			(stroke
				(width 0)
				(type default)
			)
			(fill no)
			(layer "B.Fab")
		)
		(pad "1" smd custom
			(at 0 -0.4445 270)
			(size 0.1397 0.1397)
			(layers "B.Cu" "B.Mask" "B.Paste")
			(net "HB0_R_IN0")
			(options
				(clearance outline)
				(anchor circle)
			)
			(primitives
				(gr_poly
					(pts
						(arc
							(start -0.1778 0.2794)
							(mid -0.249642 0.249642)
							(end -0.2794 0.1778)
						)
						(arc
							(start -0.2794 -0.1778)
							(mid -0.249642 -0.249642)
							(end -0.1778 -0.2794)
						)
						(arc
							(start 0.1778 -0.2794)
							(mid 0.249642 -0.249642)
							(end 0.2794 -0.1778)
						)
						(arc
							(start 0.2794 0.1778)
							(mid 0.249642 0.249642)
							(end 0.1778 0.2794)
						)
					)
					(width 0)
					(fill yes)
				)
			)
		)
		(pad "2" smd custom
			(at 0 0.4445 270)
			(size 0.1397 0.1397)
			(layers "B.Cu" "B.Mask" "B.Paste")
			(net "PEER_1B_2B_HB")
			(options
				(clearance outline)
				(anchor circle)
			)
			(primitives
				(gr_poly
					(pts
						(arc
							(start -0.1778 0.2794)
							(mid -0.249642 0.249642)
							(end -0.2794 0.1778)
						)
						(arc
							(start -0.2794 -0.1778)
							(mid -0.249642 -0.249642)
							(end -0.1778 -0.2794)
						)
						(arc
							(start 0.1778 -0.2794)
							(mid 0.249642 -0.249642)
							(end 0.2794 -0.1778)
						)
						(arc
							(start 0.2794 0.1778)
							(mid 0.249642 0.249642)
							(end 0.1778 0.2794)
						)
					)
					(width 0)
					(fill yes)
				)
			)
		)
	)
	(footprint ""
		(layer "B.Cu")
		(at 108.389166 -52.1208 -90)
		(property "Reference" "SC1008"
			(at 0 0 90)
			(layer "B.SilkS")
			(hide yes)
			(effects
				(font
					(size 1.27 1.27)
				)
				(justify mirror)
			)
		)
		(property "Value" "SCD1U16V2KX-3GP"
			(at -1.1811 -2.7051 270)
			(unlocked yes)
			(layer "B.Fab")
			(hide yes)
			(effects
				(font
					(size 1.016 1.016)
					(thickness 0.1524)
				)
				(justify mirror)
			)
		)
		(property "Device Type" "C402H22"
			(at -1.1811 -4.2291 270)
			(unlocked yes)
			(layer "B.Fab")
			(hide yes)
			(effects
				(font
					(size 1.016 1.016)
					(thickness 0.1524)
				)
				(justify mirror)
			)
		)
		(duplicate_pad_numbers_are_jumpers no)
		(fp_rect
			(start 0.4318 0.9525)
			(end -0.4318 -0.9525)
			(stroke
				(width 0)
				(type default)
			)
			(fill no)
			(layer "B.CrtYd")
		)
		(fp_rect
			(start 0.4318 0.9525)
			(end -0.4318 -0.9525)
			(stroke
				(width 0)
				(type default)
			)
			(fill no)
			(layer "B.Fab")
		)
		(pad "1" smd custom
			(at 0 -0.4445 90)
			(size 0.1524 0.1524)
			(layers "B.Cu" "B.Mask" "B.Paste")
			(net "P1V8_C")
			(options
				(clearance outline)
				(anchor circle)
			)
			(primitives
				(gr_poly
					(pts
						(arc
							(start 0.3048 0.2032)
							(mid 0.275042 0.275042)
							(end 0.2032 0.3048)
						)
						(arc
							(start -0.2032 0.3048)
							(mid -0.275042 0.275042)
							(end -0.3048 0.2032)
						)
						(arc
							(start -0.3048 -0.2032)
							(mid -0.275042 -0.275042)
							(end -0.2032 -0.3048)
						)
						(arc
							(start 0.2032 -0.3048)
							(mid 0.275042 -0.275042)
							(end 0.3048 -0.2032)
						)
					)
					(width 0)
					(fill yes)
				)
			)
		)
		(pad "2" smd custom
			(at 0 0.4445 90)
			(size 0.1524 0.1524)
			(layers "B.Cu" "B.Mask" "B.Paste")
			(net "GND")
			(options
				(clearance outline)
				(anchor circle)
			)
			(primitives
				(gr_poly
					(pts
						(arc
							(start 0.3048 0.2032)
							(mid 0.275042 0.275042)
							(end 0.2032 0.3048)
						)
						(arc
							(start -0.2032 0.3048)
							(mid -0.275042 0.275042)
							(end -0.3048 0.2032)
						)
						(arc
							(start -0.3048 -0.2032)
							(mid -0.275042 -0.275042)
							(end -0.2032 -0.3048)
						)
						(arc
							(start 0.2032 -0.3048)
							(mid 0.275042 -0.275042)
							(end 0.3048 -0.2032)
						)
					)
					(width 0)
					(fill yes)
				)
			)
		)
	)
	(footprint ""
		(layer "B.Cu")
		(at 47.82693 -76.507086)
		(property "Reference" "TP184"
			(at 0 0 0)
			(layer "B.SilkS")
			(hide yes)
			(effects
				(font
					(size 1.27 1.27)
				)
				(justify mirror)
			)
		)
		(property "Value" "TPAD32-GP"
			(at 0 -3.166364 0)
			(unlocked yes)
			(layer "B.Fab")
			(hide yes)
			(effects
				(font
					(size 1.016 1.016)
					(thickness 0.1524)
				)
				(justify mirror)
			)
		)
		(property "Device Type" "TPAD32"
			(at 0 -4.690618 0)
			(unlocked yes)
			(layer "B.Fab")
			(hide yes)
			(effects
				(font
					(size 1.016 1.016)
					(thickness 0.1524)
				)
				(justify mirror)
			)
		)
		(duplicate_pad_numbers_are_jumpers no)
		(fp_poly
			(pts
				(arc
					(start 0.4064 0)
					(mid -0.4064 0)
					(end 0.4064 0)
				)
			)
			(stroke
				(width 0)
				(type default)
			)
			(fill no)
			(layer "B.CrtYd")
		)
		(fp_poly
			(pts
				(arc
					(start 0.7112 0)
					(mid -0.7112 0)
					(end 0.7112 0)
				)
			)
			(stroke
				(width 0)
				(type default)
			)
			(fill no)
			(layer "B.Fab")
		)
		(pad "1" smd circle
			(at 0 0 180)
			(size 0.8128 0.8128)
			(layers "B.Cu" "B.Mask" "B.Paste")
			(net "INT_CONN_A_SB3")
		)
	)
	(footprint ""
		(layer "B.Cu")
		(at 103.537766 -38.5064 90)
		(property "Reference" "SC948"
			(at 0 0 90)
			(layer "B.SilkS")
			(hide yes)
			(effects
				(font
					(size 1.27 1.27)
				)
				(justify mirror)
			)
		)
		(property "Value" "SCD1U6D3V1KX-GP"
			(at 2.8321 -1.7399 90)
			(unlocked yes)
			(layer "B.Fab")
			(hide yes)
			(effects
				(font
					(size 1.016 1.016)
					(thickness 0.1524)
				)
				(justify mirror)
			)
		)
		(property "Device Type" "C0201H13"
			(at 2.8321 -3.2639 90)
			(unlocked yes)
			(layer "B.Fab")
			(hide yes)
			(effects
				(font
					(size 1.016 1.016)
					(thickness 0.1524)
				)
				(justify mirror)
			)
		)
		(duplicate_pad_numbers_are_jumpers no)
		(fp_rect
			(start 0.2794 0.6477)
			(end -0.2794 -0.6477)
			(stroke
				(width 0)
				(type default)
			)
			(fill no)
			(layer "B.CrtYd")
		)
		(fp_rect
			(start 0.2794 0.6477)
			(end -0.2794 -0.6477)
			(stroke
				(width 0)
				(type default)
			)
			(fill no)
			(layer "B.Fab")
		)
		(pad "1" smd custom
			(at 0 -0.2794 270)
			(size 0.0762 0.0762)
			(layers "B.Cu" "B.Mask" "B.Paste")
			(net "PCE_AVDD")
			(options
				(clearance outline)
				(anchor circle)
			)
			(primitives
				(gr_poly
					(pts
						(arc
							(start 0.1524 0.127)
							(mid 0.137521 0.162921)
							(end 0.1016 0.1778)
						)
						(arc
							(start -0.1016 0.1778)
							(mid -0.137521 0.162921)
							(end -0.1524 0.127)
						)
						(arc
							(start -0.1524 -0.127)
							(mid -0.137521 -0.162921)
							(end -0.1016 -0.1778)
						)
						(arc
							(start 0.1016 -0.1778)
							(mid 0.137521 -0.162921)
							(end 0.1524 -0.127)
						)
					)
					(width 0)
					(fill yes)
				)
			)
		)
		(pad "2" smd custom
			(at 0 0.2794 270)
			(size 0.0762 0.0762)
			(layers "B.Cu" "B.Mask" "B.Paste")
			(net "GND")
			(options
				(clearance outline)
				(anchor circle)
			)
			(primitives
				(gr_poly
					(pts
						(arc
							(start 0.1524 0.127)
							(mid 0.137521 0.162921)
							(end 0.1016 0.1778)
						)
						(arc
							(start -0.1016 0.1778)
							(mid -0.137521 0.162921)
							(end -0.1524 0.127)
						)
						(arc
							(start -0.1524 -0.127)
							(mid -0.137521 -0.162921)
							(end -0.1016 -0.1778)
						)
						(arc
							(start 0.1016 -0.1778)
							(mid 0.137521 -0.162921)
							(end 0.1524 -0.127)
						)
					)
					(width 0)
					(fill yes)
				)
			)
		)
	)
)
